(kicad_pcb
	(version 20260206)
	(generator "pcbnew")
	(generator_version "10.0")
	(general
		(thickness 1.6)
		(legacy_teardrops no)
	)
	(paper "A4")
	(title_block
		(title "04192023_DAF0TMB3IC0_F0TG_MB_C_brd_V02_OCP.brd")
		(comment 1 "Grand Teton / footprints 2921-2927 of 8354")
	)
	(layers
		(0 "F.Cu" signal "TOP")
		(4 "In1.Cu" signal "GND")
		(6 "In2.Cu" signal "IN1")
		(8 "In3.Cu" signal "GND1")
		(10 "In4.Cu" signal "IN2")
		(12 "In5.Cu" signal "GND2")
		(14 "In6.Cu" signal "IN3")
		(16 "In7.Cu" signal "GND3")
		(18 "In8.Cu" signal "VCC")
		(20 "In9.Cu" signal "VCC1")
		(22 "In10.Cu" signal "GND4")
		(24 "In11.Cu" signal "IN4")
		(26 "In12.Cu" signal "GND5")
		(28 "In13.Cu" signal "IN5")
		(30 "In14.Cu" signal "GND6")
		(32 "In15.Cu" signal "IN6")
		(34 "In16.Cu" signal "GND7")
		(2 "B.Cu" signal "BOTTOM")
		(9 "F.Adhes" user "F.Adhesive")
		(11 "B.Adhes" user "B.Adhesive")
		(13 "F.Paste" user "Package Geometry/Pastemask Top")
		(15 "B.Paste" user "Package Geometry/Pastemask Bottom")
		(5 "F.SilkS" user "Ref Des/Silkscreen Top")
		(7 "B.SilkS" user "Ref Des/Silkscreen Bottom")
		(1 "F.Mask" user "Board Geometry/Soldermask Top")
		(3 "B.Mask" user "Board Geometry/Soldermask Bottom")
		(17 "Dwgs.User" user "User.Drawings")
		(19 "Cmts.User" user "User.Comments")
		(21 "Eco1.User" user "User.Eco1")
		(23 "Eco2.User" user "User.Eco2")
		(25 "Edge.Cuts" user "Board Geometry/Outline")
		(27 "Margin" user)
		(31 "F.CrtYd" user "Package Geometry/Place Bound Top")
		(29 "B.CrtYd" user "Package Geometry/Place Bound Bottom")
		(35 "F.Fab" user "Ref Des/Assembly Top")
		(33 "B.Fab" user "Ref Des/Assembly Bottom")
	)
	(footprint ""
		(layer "F.Cu")
		(at 350.44761 -60.094876 180)
		(property "Reference" "R481"
			(at 0 0 180)
			(layer "F.SilkS")
			(hide yes)
			(effects
				(font
					(size 1.27 1.27)
				)
			)
		)
		(property "Value" ""
			(at 0 0 180)
			(layer "F.Fab")
			(effects
				(font
					(size 1.27 1.27)
				)
			)
		)
		(duplicate_pad_numbers_are_jumpers no)
		(fp_line
			(start 0.7874 0.4064)
			(end -0.7874 0.4064)
			(stroke
				(width 0.1524)
				(type default)
			)
			(layer "F.SilkS")
		)
		(fp_line
			(start 0.7874 -0.4064)
			(end 0.7874 0.4064)
			(stroke
				(width 0.1524)
				(type default)
			)
			(layer "F.SilkS")
		)
		(fp_line
			(start -0.7874 0.4064)
			(end -0.7874 -0.4064)
			(stroke
				(width 0.1524)
				(type default)
			)
			(layer "F.SilkS")
		)
		(fp_line
			(start -0.7874 -0.4064)
			(end 0.7874 -0.4064)
			(stroke
				(width 0.1524)
				(type default)
			)
			(layer "F.SilkS")
		)
		(fp_line
			(start 0.67945 0.3048)
			(end 0.120396 0.3048)
			(stroke
				(width 0.1)
				(type default)
			)
			(layer "F.Fab")
		)
		(fp_line
			(start 0.67945 -0.3048)
			(end 0.67945 0.3048)
			(stroke
				(width 0.1)
				(type default)
			)
			(layer "F.Fab")
		)
		(fp_line
			(start 0.12065 -0.2794)
			(end 0.12065 -0.3048)
			(stroke
				(width 0.1)
				(type default)
			)
			(layer "F.Fab")
		)
		(fp_line
			(start 0.12065 -0.3048)
			(end 0.67945 -0.3048)
			(stroke
				(width 0.1)
				(type default)
			)
			(layer "F.Fab")
		)
		(fp_line
			(start 0.120396 0.3048)
			(end 0.120396 0.2794)
			(stroke
				(width 0.1)
				(type default)
			)
			(layer "F.Fab")
		)
		(fp_line
			(start 0.120396 0.2794)
			(end -0.12065 0.2794)
			(stroke
				(width 0.1)
				(type default)
			)
			(layer "F.Fab")
		)
		(fp_line
			(start -0.12065 0.3048)
			(end -0.67945 0.3048)
			(stroke
				(width 0.1)
				(type default)
			)
			(layer "F.Fab")
		)
		(fp_line
			(start -0.12065 0.2794)
			(end -0.12065 0.3048)
			(stroke
				(width 0.1)
				(type default)
			)
			(layer "F.Fab")
		)
		(fp_line
			(start -0.12065 -0.2794)
			(end 0.12065 -0.2794)
			(stroke
				(width 0.1)
				(type default)
			)
			(layer "F.Fab")
		)
		(fp_line
			(start -0.12065 -0.305054)
			(end -0.12065 -0.2794)
			(stroke
				(width 0.1)
				(type default)
			)
			(layer "F.Fab")
		)
		(fp_line
			(start -0.67945 0.3048)
			(end -0.67945 -0.305054)
			(stroke
				(width 0.1)
				(type default)
			)
			(layer "F.Fab")
		)
		(fp_line
			(start -0.67945 -0.305054)
			(end -0.12065 -0.305054)
			(stroke
				(width 0.1)
				(type default)
			)
			(layer "F.Fab")
		)
		(pad "1" smd circle
			(at -0.40005 0 180)
			(size 0 0)
			(layers "F.Cu" "F.Mask" "F.Paste")
			(net "CPU0_XTRIG_L4")
		)
		(pad "2" smd circle
			(at 0.40005 0 180)
			(size 0 0)
			(layers "F.Cu" "F.Mask" "F.Paste")
			(net "CPU0_XTRIG_R1_L4")
		)
	)
	(footprint ""
		(layer "F.Cu")
		(at 144.36344 -30.78734 -90)
		(property "Reference" "C6014"
			(at 0 0 270)
			(layer "F.SilkS")
			(hide yes)
			(effects
				(font
					(size 1.27 1.27)
				)
			)
		)
		(property "Value" ""
			(at 0 0 270)
			(layer "F.Fab")
			(effects
				(font
					(size 1.27 1.27)
				)
			)
		)
		(duplicate_pad_numbers_are_jumpers no)
		(fp_line
			(start -0.7874 0.4064)
			(end -0.7874 -0.4064)
			(stroke
				(width 0.1524)
				(type default)
			)
			(layer "F.SilkS")
		)
		(fp_line
			(start 0.7874 0.4064)
			(end -0.7874 0.4064)
			(stroke
				(width 0.1524)
				(type default)
			)
			(layer "F.SilkS")
		)
		(fp_line
			(start -0.7874 -0.4064)
			(end 0.7874 -0.4064)
			(stroke
				(width 0.1524)
				(type default)
			)
			(layer "F.SilkS")
		)
		(fp_line
			(start 0.7874 -0.4064)
			(end 0.7874 0.4064)
			(stroke
				(width 0.1524)
				(type default)
			)
			(layer "F.SilkS")
		)
		(fp_line
			(start -0.6858 0.3048)
			(end -0.6858 -0.3048)
			(stroke
				(width 0.1)
				(type default)
			)
			(layer "F.Fab")
		)
		(fp_line
			(start -0.1016 0.3048)
			(end -0.6858 0.3048)
			(stroke
				(width 0.1)
				(type default)
			)
			(layer "F.Fab")
		)
		(fp_line
			(start 0.1016 0.3048)
			(end 0.1016 0.2794)
			(stroke
				(width 0.1)
				(type default)
			)
			(layer "F.Fab")
		)
		(fp_line
			(start 0.6858 0.3048)
			(end 0.1016 0.3048)
			(stroke
				(width 0.1)
				(type default)
			)
			(layer "F.Fab")
		)
		(fp_line
			(start -0.1016 0.2794)
			(end -0.1016 0.3048)
			(stroke
				(width 0.1)
				(type default)
			)
			(layer "F.Fab")
		)
		(fp_line
			(start 0.1016 0.2794)
			(end -0.1016 0.2794)
			(stroke
				(width 0.1)
				(type default)
			)
			(layer "F.Fab")
		)
		(fp_line
			(start -0.1016 -0.2794)
			(end 0.1016 -0.2794)
			(stroke
				(width 0.1)
				(type default)
			)
			(layer "F.Fab")
		)
		(fp_line
			(start 0.1016 -0.2794)
			(end 0.1016 -0.3048)
			(stroke
				(width 0.1)
				(type default)
			)
			(layer "F.Fab")
		)
		(fp_line
			(start -0.6858 -0.3048)
			(end -0.1016 -0.3048)
			(stroke
				(width 0.1)
				(type default)
			)
			(layer "F.Fab")
		)
		(fp_line
			(start -0.1016 -0.3048)
			(end -0.1016 -0.2794)
			(stroke
				(width 0.1)
				(type default)
			)
			(layer "F.Fab")
		)
		(fp_line
			(start 0.1016 -0.3048)
			(end 0.6858 -0.3048)
			(stroke
				(width 0.1)
				(type default)
			)
			(layer "F.Fab")
		)
		(fp_line
			(start 0.6858 -0.3048)
			(end 0.6858 0.3048)
			(stroke
				(width 0.1)
				(type default)
			)
			(layer "F.Fab")
		)
		(pad "1" smd rect
			(at -0.40005 0 90)
			(size 0.4572 0.508)
			(layers "F.Cu" "F.Mask" "F.Paste")
			(net "USB3_CPU0_BMC_TX_DN")
		)
		(pad "2" smd rect
			(at 0.40005 0 90)
			(size 0.4572 0.508)
			(layers "F.Cu" "F.Mask" "F.Paste")
			(net "USB3_CPU0_BMC_TX_C2_DN")
		)
	)
	(footprint ""
		(layer "F.Cu")
		(at 185.095642 -413.64408 90)
		(property "Reference" "R8004"
			(at 0 0 90)
			(layer "F.SilkS")
			(hide yes)
			(effects
				(font
					(size 1.27 1.27)
				)
			)
		)
		(property "Value" ""
			(at 0 0 90)
			(layer "F.Fab")
			(effects
				(font
					(size 1.27 1.27)
				)
			)
		)
		(duplicate_pad_numbers_are_jumpers no)
		(fp_line
			(start 0.7874 -0.4064)
			(end 0.7874 0.4064)
			(stroke
				(width 0.1524)
				(type default)
			)
			(layer "F.SilkS")
		)
		(fp_line
			(start -0.7874 -0.4064)
			(end 0.7874 -0.4064)
			(stroke
				(width 0.1524)
				(type default)
			)
			(layer "F.SilkS")
		)
		(fp_line
			(start 0.7874 0.4064)
			(end -0.7874 0.4064)
			(stroke
				(width 0.1524)
				(type default)
			)
			(layer "F.SilkS")
		)
		(fp_line
			(start -0.7874 0.4064)
			(end -0.7874 -0.4064)
			(stroke
				(width 0.1524)
				(type default)
			)
			(layer "F.SilkS")
		)
		(fp_line
			(start -0.12065 -0.305054)
			(end -0.12065 -0.2794)
			(stroke
				(width 0.1)
				(type default)
			)
			(layer "F.Fab")
		)
		(fp_line
			(start -0.67945 -0.305054)
			(end -0.12065 -0.305054)
			(stroke
				(width 0.1)
				(type default)
			)
			(layer "F.Fab")
		)
		(fp_line
			(start 0.67945 -0.3048)
			(end 0.67945 0.3048)
			(stroke
				(width 0.1)
				(type default)
			)
			(layer "F.Fab")
		)
		(fp_line
			(start 0.12065 -0.3048)
			(end 0.67945 -0.3048)
			(stroke
				(width 0.1)
				(type default)
			)
			(layer "F.Fab")
		)
		(fp_line
			(start 0.12065 -0.2794)
			(end 0.12065 -0.3048)
			(stroke
				(width 0.1)
				(type default)
			)
			(layer "F.Fab")
		)
		(fp_line
			(start -0.12065 -0.2794)
			(end 0.12065 -0.2794)
			(stroke
				(width 0.1)
				(type default)
			)
			(layer "F.Fab")
		)
		(fp_line
			(start 0.120396 0.2794)
			(end -0.12065 0.2794)
			(stroke
				(width 0.1)
				(type default)
			)
			(layer "F.Fab")
		)
		(fp_line
			(start -0.12065 0.2794)
			(end -0.12065 0.3048)
			(stroke
				(width 0.1)
				(type default)
			)
			(layer "F.Fab")
		)
		(fp_line
			(start 0.67945 0.3048)
			(end 0.120396 0.3048)
			(stroke
				(width 0.1)
				(type default)
			)
			(layer "F.Fab")
		)
		(fp_line
			(start 0.120396 0.3048)
			(end 0.120396 0.2794)
			(stroke
				(width 0.1)
				(type default)
			)
			(layer "F.Fab")
		)
		(fp_line
			(start -0.12065 0.3048)
			(end -0.67945 0.3048)
			(stroke
				(width 0.1)
				(type default)
			)
			(layer "F.Fab")
		)
		(fp_line
			(start -0.67945 0.3048)
			(end -0.67945 -0.305054)
			(stroke
				(width 0.1)
				(type default)
			)
			(layer "F.Fab")
		)
		(pad "1" smd circle
			(at -0.40005 0 90)
			(size 0 0)
			(layers "F.Cu" "F.Mask" "F.Paste")
			(net "PRSNT_SWB_ISO_N")
		)
		(pad "2" smd circle
			(at 0.40005 0 90)
			(size 0 0)
			(layers "F.Cu" "F.Mask" "F.Paste")
			(net "PRSNT_SWB_ISO_R1_N")
		)
	)
	(footprint ""
		(layer "F.Cu")
		(at 169.368724 -380.385828)
		(property "Reference" "C742"
			(at 0 0 0)
			(layer "F.SilkS")
			(hide yes)
			(effects
				(font
					(size 1.27 1.27)
				)
			)
		)
		(property "Value" ""
			(at 0 0 0)
			(layer "F.Fab")
			(effects
				(font
					(size 1.27 1.27)
				)
			)
		)
		(duplicate_pad_numbers_are_jumpers no)
		(fp_line
			(start -0.299974 -0.150114)
			(end 0.299974 -0.150114)
			(stroke
				(width 0.1)
				(type default)
			)
			(layer "F.Fab")
		)
		(fp_line
			(start -0.299974 0.150114)
			(end -0.299974 -0.150114)
			(stroke
				(width 0.1)
				(type default)
			)
			(layer "F.Fab")
		)
		(fp_line
			(start 0.299974 -0.150114)
			(end 0.299974 0.150114)
			(stroke
				(width 0.1)
				(type default)
			)
			(layer "F.Fab")
		)
		(fp_line
			(start 0.299974 0.150114)
			(end -0.299974 0.150114)
			(stroke
				(width 0.1)
				(type default)
			)
			(layer "F.Fab")
		)
		(pad "1" smd rect
			(at -0.2667 0)
			(size 0.3048 0.381)
			(layers "F.Cu" "F.Mask" "F.Paste")
			(net "P5E_CPU1_P2_TX_C_DN<15>")
		)
		(pad "2" smd rect
			(at 0.2667 0)
			(size 0.3048 0.381)
			(layers "F.Cu" "F.Mask" "F.Paste")
			(net "P5E_CPU1_P2_TX_DN<15>")
		)
	)
	(footprint ""
		(layer "F.Cu")
		(at 271.585944 -100.446078 -90)
		(property "Reference" "C1507"
			(at 0 0 270)
			(layer "F.SilkS")
			(hide yes)
			(effects
				(font
					(size 1.27 1.27)
				)
			)
		)
		(property "Value" ""
			(at 0 0 270)
			(layer "F.Fab")
			(effects
				(font
					(size 1.27 1.27)
				)
			)
		)
		(duplicate_pad_numbers_are_jumpers no)
		(fp_line
			(start -0.7874 0.4064)
			(end -0.7874 -0.4064)
			(stroke
				(width 0.1524)
				(type default)
			)
			(layer "F.SilkS")
		)
		(fp_line
			(start 0.7874 0.4064)
			(end -0.7874 0.4064)
			(stroke
				(width 0.1524)
				(type default)
			)
			(layer "F.SilkS")
		)
		(fp_line
			(start -0.7874 -0.4064)
			(end 0.7874 -0.4064)
			(stroke
				(width 0.1524)
				(type default)
			)
			(layer "F.SilkS")
		)
		(fp_line
			(start 0.7874 -0.4064)
			(end 0.7874 0.4064)
			(stroke
				(width 0.1524)
				(type default)
			)
			(layer "F.SilkS")
		)
		(fp_line
			(start -0.67945 0.3048)
			(end -0.67945 -0.305054)
			(stroke
				(width 0.1)
				(type default)
			)
			(layer "F.Fab")
		)
		(fp_line
			(start -0.12065 0.3048)
			(end -0.67945 0.3048)
			(stroke
				(width 0.1)
				(type default)
			)
			(layer "F.Fab")
		)
		(fp_line
			(start 0.120396 0.3048)
			(end 0.120396 0.2794)
			(stroke
				(width 0.1)
				(type default)
			)
			(layer "F.Fab")
		)
		(fp_line
			(start 0.67945 0.3048)
			(end 0.120396 0.3048)
			(stroke
				(width 0.1)
				(type default)
			)
			(layer "F.Fab")
		)
		(fp_line
			(start -0.12065 0.2794)
			(end -0.12065 0.3048)
			(stroke
				(width 0.1)
				(type default)
			)
			(layer "F.Fab")
		)
		(fp_line
			(start 0.120396 0.2794)
			(end -0.12065 0.2794)
			(stroke
				(width 0.1)
				(type default)
			)
			(layer "F.Fab")
		)
		(fp_line
			(start -0.12065 -0.2794)
			(end 0.12065 -0.2794)
			(stroke
				(width 0.1)
				(type default)
			)
			(layer "F.Fab")
		)
		(fp_line
			(start 0.12065 -0.2794)
			(end 0.12065 -0.3048)
			(stroke
				(width 0.1)
				(type default)
			)
			(layer "F.Fab")
		)
		(fp_line
			(start 0.12065 -0.3048)
			(end 0.67945 -0.3048)
			(stroke
				(width 0.1)
				(type default)
			)
			(layer "F.Fab")
		)
		(fp_line
			(start 0.67945 -0.3048)
			(end 0.67945 0.3048)
			(stroke
				(width 0.1)
				(type default)
			)
			(layer "F.Fab")
		)
		(fp_line
			(start -0.67945 -0.305054)
			(end -0.12065 -0.305054)
			(stroke
				(width 0.1)
				(type default)
			)
			(layer "F.Fab")
		)
		(fp_line
			(start -0.12065 -0.305054)
			(end -0.12065 -0.2794)
			(stroke
				(width 0.1)
				(type default)
			)
			(layer "F.Fab")
		)
		(pad "1" smd circle
			(at -0.40005 0 270)
			(size 0 0)
			(layers "F.Cu" "F.Mask" "F.Paste")
			(net "PVDD18_S5_P0")
		)
		(pad "2" smd circle
			(at 0.40005 0 270)
			(size 0 0)
			(layers "F.Cu" "F.Mask" "F.Paste")
			(net "GND")
		)
	)
	(footprint ""
		(layer "F.Cu")
		(at 119.36857 -169.258234 -90)
		(property "Reference" "PC319"
			(at 0 0 270)
			(layer "F.SilkS")
			(hide yes)
			(effects
				(font
					(size 1.27 1.27)
				)
			)
		)
		(property "Value" ""
			(at 0 0 270)
			(layer "F.Fab")
			(effects
				(font
					(size 1.27 1.27)
				)
			)
		)
		(duplicate_pad_numbers_are_jumpers no)
		(fp_line
			(start -0.7874 0.4064)
			(end -0.7874 -0.4064)
			(stroke
				(width 0.1524)
				(type default)
			)
			(layer "F.SilkS")
		)
		(fp_line
			(start -0.286766 0.4064)
			(end -0.7874 0.4064)
			(stroke
				(width 0.1524)
				(type default)
			)
			(layer "F.SilkS")
		)
		(fp_line
			(start 0.7874 0.4064)
			(end 0.348234 0.4064)
			(stroke
				(width 0.1524)
				(type default)
			)
			(layer "F.SilkS")
		)
		(fp_line
			(start -0.7874 -0.4064)
			(end 0.7874 -0.4064)
			(stroke
				(width 0.1524)
				(type default)
			)
			(layer "F.SilkS")
		)
		(fp_line
			(start 0.7874 -0.4064)
			(end 0.7874 0.4064)
			(stroke
				(width 0.1524)
				(type default)
			)
			(layer "F.SilkS")
		)
		(fp_line
			(start -0.67945 0.3048)
			(end -0.67945 -0.305054)
			(stroke
				(width 0.1)
				(type default)
			)
			(layer "F.Fab")
		)
		(fp_line
			(start -0.12065 0.3048)
			(end -0.67945 0.3048)
			(stroke
				(width 0.1)
				(type default)
			)
			(layer "F.Fab")
		)
		(fp_line
			(start 0.120396 0.3048)
			(end 0.120396 0.2794)
			(stroke
				(width 0.1)
				(type default)
			)
			(layer "F.Fab")
		)
		(fp_line
			(start 0.67945 0.3048)
			(end 0.120396 0.3048)
			(stroke
				(width 0.1)
				(type default)
			)
			(layer "F.Fab")
		)
		(fp_line
			(start -0.12065 0.2794)
			(end -0.12065 0.3048)
			(stroke
				(width 0.1)
				(type default)
			)
			(layer "F.Fab")
		)
		(fp_line
			(start 0.120396 0.2794)
			(end -0.12065 0.2794)
			(stroke
				(width 0.1)
				(type default)
			)
			(layer "F.Fab")
		)
		(fp_line
			(start -0.12065 -0.2794)
			(end 0.12065 -0.2794)
			(stroke
				(width 0.1)
				(type default)
			)
			(layer "F.Fab")
		)
		(fp_line
			(start 0.12065 -0.2794)
			(end 0.12065 -0.3048)
			(stroke
				(width 0.1)
				(type default)
			)
			(layer "F.Fab")
		)
		(fp_line
			(start 0.12065 -0.3048)
			(end 0.67945 -0.3048)
			(stroke
				(width 0.1)
				(type default)
			)
			(layer "F.Fab")
		)
		(fp_line
			(start 0.67945 -0.3048)
			(end 0.67945 0.3048)
			(stroke
				(width 0.1)
				(type default)
			)
			(layer "F.Fab")
		)
		(fp_line
			(start -0.67945 -0.305054)
			(end -0.12065 -0.305054)
			(stroke
				(width 0.1)
				(type default)
			)
			(layer "F.Fab")
		)
		(fp_line
			(start -0.12065 -0.305054)
			(end -0.12065 -0.2794)
			(stroke
				(width 0.1)
				(type default)
			)
			(layer "F.Fab")
		)
		(pad "1" smd circle
			(at -0.40005 0 270)
			(size 0 0)
			(layers "F.Cu" "F.Mask" "F.Paste")
			(net "PVDDCR_SOC_P1_VCC1")
		)
		(pad "2" smd circle
			(at 0.40005 0 270)
			(size 0 0)
			(layers "F.Cu" "F.Mask" "F.Paste")
			(net "GND")
		)
	)
	(footprint ""
		(layer "F.Cu")
		(at 306.501038 -424.956986)
		(property "Reference" "R4139"
			(at 0 0 0)
			(layer "F.SilkS")
			(hide yes)
			(effects
				(font
					(size 1.27 1.27)
				)
			)
		)
		(property "Value" ""
			(at 0 0 0)
			(layer "F.Fab")
			(effects
				(font
					(size 1.27 1.27)
				)
			)
		)
		(duplicate_pad_numbers_are_jumpers no)
		(fp_line
			(start -0.7874 -0.4064)
			(end 0.7874 -0.4064)
			(stroke
				(width 0.1524)
				(type default)
			)
			(layer "F.SilkS")
		)
		(fp_line
			(start -0.7874 0.4064)
			(end -0.7874 -0.4064)
			(stroke
				(width 0.1524)
				(type default)
			)
			(layer "F.SilkS")
		)
		(fp_line
			(start 0.7874 -0.4064)
			(end 0.7874 0.4064)
			(stroke
				(width 0.1524)
				(type default)
			)
			(layer "F.SilkS")
		)
		(fp_line
			(start 0.7874 0.4064)
			(end -0.7874 0.4064)
			(stroke
				(width 0.1524)
				(type default)
			)
			(layer "F.SilkS")
		)
		(fp_line
			(start -0.67945 -0.305054)
			(end -0.12065 -0.305054)
			(stroke
				(width 0.1)
				(type default)
			)
			(layer "F.Fab")
		)
		(fp_line
			(start -0.67945 0.3048)
			(end -0.67945 -0.305054)
			(stroke
				(width 0.1)
				(type default)
			)
			(layer "F.Fab")
		)
		(fp_line
			(start -0.12065 -0.305054)
			(end -0.12065 -0.2794)
			(stroke
				(width 0.1)
				(type default)
			)
			(layer "F.Fab")
		)
		(fp_line
			(start -0.12065 -0.2794)
			(end 0.12065 -0.2794)
			(stroke
				(width 0.1)
				(type default)
			)
			(layer "F.Fab")
		)
		(fp_line
			(start -0.12065 0.2794)
			(end -0.12065 0.3048)
			(stroke
				(width 0.1)
				(type default)
			)
			(layer "F.Fab")
		)
		(fp_line
			(start -0.12065 0.3048)
			(end -0.67945 0.3048)
			(stroke
				(width 0.1)
				(type default)
			)
			(layer "F.Fab")
		)
		(fp_line
			(start 0.120396 0.2794)
			(end -0.12065 0.2794)
			(stroke
				(width 0.1)
				(type default)
			)
			(layer "F.Fab")
		)
		(fp_line
			(start 0.120396 0.3048)
			(end 0.120396 0.2794)
			(stroke
				(width 0.1)
				(type default)
			)
			(layer "F.Fab")
		)
		(fp_line
			(start 0.12065 -0.3048)
			(end 0.67945 -0.3048)
			(stroke
				(width 0.1)
				(type default)
			)
			(layer "F.Fab")
		)
		(fp_line
			(start 0.12065 -0.2794)
			(end 0.12065 -0.3048)
			(stroke
				(width 0.1)
				(type default)
			)
			(layer "F.Fab")
		)
		(fp_line
			(start 0.67945 -0.3048)
			(end 0.67945 0.3048)
			(stroke
				(width 0.1)
				(type default)
			)
			(layer "F.Fab")
		)
		(fp_line
			(start 0.67945 0.3048)
			(end 0.120396 0.3048)
			(stroke
				(width 0.1)
				(type default)
			)
			(layer "F.Fab")
		)
		(pad "1" smd circle
			(at -0.40005 0)
			(size 0 0)
			(layers "F.Cu" "F.Mask" "F.Paste")
			(net "P3V3_AUX")
		)
		(pad "2" smd circle
			(at 0.40005 0)
			(size 0 0)
			(layers "F.Cu" "F.Mask" "F.Paste")
			(net "PRSNT_CABLE_GPU_A2")
		)
	)
)
